(kicad_pcb
	(version 20241229)
	(generator "pcbnew")
	(generator_version "9.0")
	(general
		(thickness 1.599998)
		(legacy_teardrops no)
	)
	(paper "A4")
	(title_block
		(title "Artix - Datacenter Secure Control Module (DC-SCM)")
		(date "2024-11-06")
		(rev "1.1.3")
		(comment 9 "footprints 507-511 of 544")
	)
	(layers
		(0 "F.Cu" signal)
		(4 "In1.Cu" signal)
		(6 "In2.Cu" signal)
		(8 "In3.Cu" signal)
		(10 "In4.Cu" signal)
		(12 "In5.Cu" signal)
		(14 "In6.Cu" signal)
		(2 "B.Cu" signal)
		(9 "F.Adhes" user "F.Adhesive")
		(11 "B.Adhes" user "B.Adhesive")
		(13 "F.Paste" user)
		(15 "B.Paste" user)
		(5 "F.SilkS" user "F.Silkscreen")
		(7 "B.SilkS" user "B.Silkscreen")
		(1 "F.Mask" user)
		(3 "B.Mask" user)
		(17 "Dwgs.User" user "User.Drawings")
		(19 "Cmts.User" user "User.Comments")
		(21 "Eco1.User" user "User.Eco1")
		(23 "Eco2.User" user "User.Eco2")
		(25 "Edge.Cuts" user)
		(27 "Margin" user)
		(31 "F.CrtYd" user "F.Courtyard")
		(29 "B.CrtYd" user "B.Courtyard")
		(35 "F.Fab" user)
		(33 "B.Fab" user)
	)
	(footprint "antmicro-footprints:C_0402_1005Metric"
		(layer "B.Cu")
		(at 96.69 99.49)
		(descr "Capacitor SMD 0402")
		(tags "capacitor SMD 0402")
		(property "Reference" "C201"
			(at -9.19 -0.077 0)
			(layer "B.SilkS")
			(effects
				(font
					(size 0.7 0.7)
					(thickness 0.15)
				)
				(justify right bottom mirror)
			)
		)
		(property "Value" "C_470n_0402"
			(at 0 -1.4 0)
			(layer "B.Fab")
			(effects
				(font
					(size 0.7 0.7)
					(thickness 0.15)
				)
				(justify right bottom mirror)
			)
		)
		(property "Datasheet" "https://product.tdk.com/en/search/capacitor/ceramic/mlcc/info?part_no=C1005X5R1E474M050BB"
			(at 0 0 0)
			(layer "F.Fab")
			(hide yes)
			(effects
				(font
					(size 1.27 1.27)
					(thickness 0.15)
				)
			)
		)
		(property "Description" "SMD Multilayer Ceramic Capacitor, 0.47 µF, 25 V, 0402 [1005 Metric], ± 20%, X5R, C"
			(at 0 0 0)
			(layer "F.Fab")
			(hide yes)
			(effects
				(font
					(size 1.27 1.27)
					(thickness 0.15)
				)
			)
		)
		(property "Author" "Antmicro"
			(at 0 0 0)
			(layer "B.Fab")
			(hide yes)
			(effects
				(font
					(size 1 1)
					(thickness 0.15)
				)
				(justify mirror)
			)
		)
		(property "Dielectric" ""
			(at 0 0 0)
			(layer "B.Fab")
			(hide yes)
			(effects
				(font
					(size 1 1)
					(thickness 0.15)
				)
				(justify mirror)
			)
		)
		(property "License" "Apache-2.0"
			(at 0 0 0)
			(layer "B.Fab")
			(hide yes)
			(effects
				(font
					(size 1 1)
					(thickness 0.15)
				)
				(justify mirror)
			)
		)
		(property "MPN" "C1005X5R1E474M050BB"
			(at 0 0 0)
			(layer "B.Fab")
			(hide yes)
			(effects
				(font
					(size 1 1)
					(thickness 0.15)
				)
				(justify mirror)
			)
		)
		(property "Manufacturer" "TDK"
			(at 0 0 0)
			(layer "B.Fab")
			(hide yes)
			(effects
				(font
					(size 1 1)
					(thickness 0.15)
				)
				(justify mirror)
			)
		)
		(property "Val" "470n"
			(at 0 0 0)
			(layer "B.Fab")
			(hide yes)
			(effects
				(font
					(size 1 1)
					(thickness 0.15)
				)
				(justify mirror)
			)
		)
		(property "Voltage" ""
			(at 0 0 0)
			(layer "B.Fab")
			(hide yes)
			(effects
				(font
					(size 1 1)
					(thickness 0.15)
				)
				(justify mirror)
			)
		)
		(sheetname "/Ethernet/")
		(sheetfile "ethernet.kicad_sch")
		(attr smd)
		(fp_rect
			(start -0.925 0.47)
			(end 0.925 -0.47)
			(stroke
				(width 0.05)
				(type default)
			)
			(fill no)
			(layer "B.CrtYd")
		)
		(fp_line
			(start -0.494 -0.248)
			(end -0.494 0.25)
			(stroke
				(width 0.15)
				(type solid)
			)
			(layer "B.Fab")
		)
		(fp_line
			(start -0.494 0.25)
			(end 0.504 0.25)
			(stroke
				(width 0.15)
				(type solid)
			)
			(layer "B.Fab")
		)
		(fp_line
			(start 0.504 -0.248)
			(end -0.494 -0.248)
			(stroke
				(width 0.15)
				(type solid)
			)
			(layer "B.Fab")
		)
		(fp_line
			(start 0.504 0.25)
			(end 0.504 -0.248)
			(stroke
				(width 0.15)
				(type solid)
			)
			(layer "B.Fab")
		)
		(pad "1" smd roundrect
			(at -0.48 0)
			(size 0.59 0.64)
			(layers "B.Cu" "B.Mask" "B.Paste")
			(roundrect_rratio 0.25)
			(net 1 "GND")
			(pintype "passive")
		)
		(pad "2" smd roundrect
			(at 0.48 0)
			(size 0.59 0.64)
			(layers "B.Cu" "B.Mask" "B.Paste")
			(roundrect_rratio 0.25)
			(net 339 "VCC1V2")
			(pintype "passive")
		)
	)
	(footprint "antmicro-footprints:C_0402_1005Metric"
		(layer "B.Cu")
		(at 96.69 95.94)
		(descr "Capacitor SMD 0402")
		(tags "capacitor SMD 0402")
		(property "Reference" "C202"
			(at -9.2 0.2 0)
			(layer "B.SilkS")
			(effects
				(font
					(size 0.7 0.7)
					(thickness 0.15)
				)
				(justify right bottom mirror)
			)
		)
		(property "Value" "C_470n_0402"
			(at 0 -1.4 0)
			(layer "B.Fab")
			(effects
				(font
					(size 0.7 0.7)
					(thickness 0.15)
				)
				(justify right bottom mirror)
			)
		)
		(property "Datasheet" "https://product.tdk.com/en/search/capacitor/ceramic/mlcc/info?part_no=C1005X5R1E474M050BB"
			(at 0 0 0)
			(layer "F.Fab")
			(hide yes)
			(effects
				(font
					(size 1.27 1.27)
					(thickness 0.15)
				)
			)
		)
		(property "Description" "SMD Multilayer Ceramic Capacitor, 0.47 µF, 25 V, 0402 [1005 Metric], ± 20%, X5R, C"
			(at 0 0 0)
			(layer "F.Fab")
			(hide yes)
			(effects
				(font
					(size 1.27 1.27)
					(thickness 0.15)
				)
			)
		)
		(property "Author" "Antmicro"
			(at 0 0 0)
			(layer "B.Fab")
			(hide yes)
			(effects
				(font
					(size 1 1)
					(thickness 0.15)
				)
				(justify mirror)
			)
		)
		(property "Dielectric" ""
			(at 0 0 0)
			(layer "B.Fab")
			(hide yes)
			(effects
				(font
					(size 1 1)
					(thickness 0.15)
				)
				(justify mirror)
			)
		)
		(property "License" "Apache-2.0"
			(at 0 0 0)
			(layer "B.Fab")
			(hide yes)
			(effects
				(font
					(size 1 1)
					(thickness 0.15)
				)
				(justify mirror)
			)
		)
		(property "MPN" "C1005X5R1E474M050BB"
			(at 0 0 0)
			(layer "B.Fab")
			(hide yes)
			(effects
				(font
					(size 1 1)
					(thickness 0.15)
				)
				(justify mirror)
			)
		)
		(property "Manufacturer" "TDK"
			(at 0 0 0)
			(layer "B.Fab")
			(hide yes)
			(effects
				(font
					(size 1 1)
					(thickness 0.15)
				)
				(justify mirror)
			)
		)
		(property "Val" "470n"
			(at 0 0 0)
			(layer "B.Fab")
			(hide yes)
			(effects
				(font
					(size 1 1)
					(thickness 0.15)
				)
				(justify mirror)
			)
		)
		(property "Voltage" ""
			(at 0 0 0)
			(layer "B.Fab")
			(hide yes)
			(effects
				(font
					(size 1 1)
					(thickness 0.15)
				)
				(justify mirror)
			)
		)
		(sheetname "/Ethernet/")
		(sheetfile "ethernet.kicad_sch")
		(attr smd)
		(fp_rect
			(start -0.925 0.47)
			(end 0.925 -0.47)
			(stroke
				(width 0.05)
				(type default)
			)
			(fill no)
			(layer "B.CrtYd")
		)
		(fp_line
			(start -0.494 -0.248)
			(end -0.494 0.25)
			(stroke
				(width 0.15)
				(type solid)
			)
			(layer "B.Fab")
		)
		(fp_line
			(start -0.494 0.25)
			(end 0.504 0.25)
			(stroke
				(width 0.15)
				(type solid)
			)
			(layer "B.Fab")
		)
		(fp_line
			(start 0.504 -0.248)
			(end -0.494 -0.248)
			(stroke
				(width 0.15)
				(type solid)
			)
			(layer "B.Fab")
		)
		(fp_line
			(start 0.504 0.25)
			(end 0.504 -0.248)
			(stroke
				(width 0.15)
				(type solid)
			)
			(layer "B.Fab")
		)
		(pad "1" smd roundrect
			(at -0.48 0)
			(size 0.59 0.64)
			(layers "B.Cu" "B.Mask" "B.Paste")
			(roundrect_rratio 0.25)
			(net 1 "GND")
			(pintype "passive")
		)
		(pad "2" smd roundrect
			(at 0.48 0)
			(size 0.59 0.64)
			(layers "B.Cu" "B.Mask" "B.Paste")
			(roundrect_rratio 0.25)
			(net 2 "VCC3V3")
			(pintype "passive")
		)
	)
	(footprint "antmicro-footprints:C_0402_1005Metric"
		(layer "B.Cu")
		(at 96.69 98.477)
		(descr "Capacitor SMD 0402")
		(tags "capacitor SMD 0402")
		(property "Reference" "C210"
			(at -9.19 -0.077 0)
			(layer "B.SilkS")
			(effects
				(font
					(size 0.7 0.7)
					(thickness 0.15)
				)
				(justify right bottom mirror)
			)
		)
		(property "Value" "C_10n_0402"
			(at 0 -1.4 0)
			(layer "B.Fab")
			(effects
				(font
					(size 0.7 0.7)
					(thickness 0.15)
				)
				(justify right bottom mirror)
			)
		)
		(property "Datasheet" "https://www.murata.com/products/productdetail?partno=GRM155R71H103KA88%23"
			(at 0 0 0)
			(layer "F.Fab")
			(hide yes)
			(effects
				(font
					(size 1.27 1.27)
					(thickness 0.15)
				)
			)
		)
		(property "Description" "SMD Multilayer Ceramic Capacitor, 10000 pF, 50 V, 0402 [1005 Metric], ± 10%, X7R, GRM Series"
			(at 0 0 0)
			(layer "F.Fab")
			(hide yes)
			(effects
				(font
					(size 1.27 1.27)
					(thickness 0.15)
				)
			)
		)
		(property "Author" "Antmicro"
			(at 0 0 0)
			(layer "B.Fab")
			(hide yes)
			(effects
				(font
					(size 1 1)
					(thickness 0.15)
				)
				(justify mirror)
			)
		)
		(property "Dielectric" "X7R"
			(at 0 0 0)
			(layer "B.Fab")
			(hide yes)
			(effects
				(font
					(size 1 1)
					(thickness 0.15)
				)
				(justify mirror)
			)
		)
		(property "License" "Apache-2.0"
			(at 0 0 0)
			(layer "B.Fab")
			(hide yes)
			(effects
				(font
					(size 1 1)
					(thickness 0.15)
				)
				(justify mirror)
			)
		)
		(property "MPN" "GRM155R71H103KA88D"
			(at 0 0 0)
			(layer "B.Fab")
			(hide yes)
			(effects
				(font
					(size 1 1)
					(thickness 0.15)
				)
				(justify mirror)
			)
		)
		(property "Manufacturer" "Murata"
			(at 0 0 0)
			(layer "B.Fab")
			(hide yes)
			(effects
				(font
					(size 1 1)
					(thickness 0.15)
				)
				(justify mirror)
			)
		)
		(property "Val" "10n"
			(at 0 0 0)
			(layer "B.Fab")
			(hide yes)
			(effects
				(font
					(size 1 1)
					(thickness 0.15)
				)
				(justify mirror)
			)
		)
		(property "Voltage" "50V"
			(at 0 0 0)
			(layer "B.Fab")
			(hide yes)
			(effects
				(font
					(size 1 1)
					(thickness 0.15)
				)
				(justify mirror)
			)
		)
		(sheetname "/Ethernet/")
		(sheetfile "ethernet.kicad_sch")
		(attr smd)
		(fp_rect
			(start -0.925 0.47)
			(end 0.925 -0.47)
			(stroke
				(width 0.05)
				(type default)
			)
			(fill no)
			(layer "B.CrtYd")
		)
		(fp_line
			(start -0.494 -0.248)
			(end -0.494 0.25)
			(stroke
				(width 0.15)
				(type solid)
			)
			(layer "B.Fab")
		)
		(fp_line
			(start -0.494 0.25)
			(end 0.504 0.25)
			(stroke
				(width 0.15)
				(type solid)
			)
			(layer "B.Fab")
		)
		(fp_line
			(start 0.504 -0.248)
			(end -0.494 -0.248)
			(stroke
				(width 0.15)
				(type solid)
			)
			(layer "B.Fab")
		)
		(fp_line
			(start 0.504 0.25)
			(end 0.504 -0.248)
			(stroke
				(width 0.15)
				(type solid)
			)
			(layer "B.Fab")
		)
		(pad "1" smd roundrect
			(at -0.48 0)
			(size 0.59 0.64)
			(layers "B.Cu" "B.Mask" "B.Paste")
			(roundrect_rratio 0.25)
			(net 1 "GND")
			(pintype "passive")
		)
		(pad "2" smd roundrect
			(at 0.48 0)
			(size 0.59 0.64)
			(layers "B.Cu" "B.Mask" "B.Paste")
			(roundrect_rratio 0.25)
			(net 339 "VCC1V2")
			(pintype "passive")
		)
	)
	(footprint "antmicro-footprints:C_0402_1005Metric"
		(layer "B.Cu")
		(at 96.7 95)
		(descr "Capacitor SMD 0402")
		(tags "capacitor SMD 0402")
		(property "Reference" "C216"
			(at -9.2 0.2 0)
			(layer "B.SilkS")
			(effects
				(font
					(size 0.7 0.7)
					(thickness 0.15)
				)
				(justify right bottom mirror)
			)
		)
		(property "Value" "C_10n_0402"
			(at 0 -1.4 0)
			(layer "B.Fab")
			(effects
				(font
					(size 0.7 0.7)
					(thickness 0.15)
				)
				(justify right bottom mirror)
			)
		)
		(property "Datasheet" "https://www.murata.com/products/productdetail?partno=GRM155R71H103KA88%23"
			(at 0 0 0)
			(layer "F.Fab")
			(hide yes)
			(effects
				(font
					(size 1.27 1.27)
					(thickness 0.15)
				)
			)
		)
		(property "Description" "SMD Multilayer Ceramic Capacitor, 10000 pF, 50 V, 0402 [1005 Metric], ± 10%, X7R, GRM Series"
			(at 0 0 0)
			(layer "F.Fab")
			(hide yes)
			(effects
				(font
					(size 1.27 1.27)
					(thickness 0.15)
				)
			)
		)
		(property "Author" "Antmicro"
			(at 0 0 0)
			(layer "B.Fab")
			(hide yes)
			(effects
				(font
					(size 1 1)
					(thickness 0.15)
				)
				(justify mirror)
			)
		)
		(property "Dielectric" "X7R"
			(at 0 0 0)
			(layer "B.Fab")
			(hide yes)
			(effects
				(font
					(size 1 1)
					(thickness 0.15)
				)
				(justify mirror)
			)
		)
		(property "License" "Apache-2.0"
			(at 0 0 0)
			(layer "B.Fab")
			(hide yes)
			(effects
				(font
					(size 1 1)
					(thickness 0.15)
				)
				(justify mirror)
			)
		)
		(property "MPN" "GRM155R71H103KA88D"
			(at 0 0 0)
			(layer "B.Fab")
			(hide yes)
			(effects
				(font
					(size 1 1)
					(thickness 0.15)
				)
				(justify mirror)
			)
		)
		(property "Manufacturer" "Murata"
			(at 0 0 0)
			(layer "B.Fab")
			(hide yes)
			(effects
				(font
					(size 1 1)
					(thickness 0.15)
				)
				(justify mirror)
			)
		)
		(property "Val" "10n"
			(at 0 0 0)
			(layer "B.Fab")
			(hide yes)
			(effects
				(font
					(size 1 1)
					(thickness 0.15)
				)
				(justify mirror)
			)
		)
		(property "Voltage" "50V"
			(at 0 0 0)
			(layer "B.Fab")
			(hide yes)
			(effects
				(font
					(size 1 1)
					(thickness 0.15)
				)
				(justify mirror)
			)
		)
		(sheetname "/Ethernet/")
		(sheetfile "ethernet.kicad_sch")
		(attr smd)
		(fp_rect
			(start -0.925 0.47)
			(end 0.925 -0.47)
			(stroke
				(width 0.05)
				(type default)
			)
			(fill no)
			(layer "B.CrtYd")
		)
		(fp_line
			(start -0.494 -0.248)
			(end -0.494 0.25)
			(stroke
				(width 0.15)
				(type solid)
			)
			(layer "B.Fab")
		)
		(fp_line
			(start -0.494 0.25)
			(end 0.504 0.25)
			(stroke
				(width 0.15)
				(type solid)
			)
			(layer "B.Fab")
		)
		(fp_line
			(start 0.504 -0.248)
			(end -0.494 -0.248)
			(stroke
				(width 0.15)
				(type solid)
			)
			(layer "B.Fab")
		)
		(fp_line
			(start 0.504 0.25)
			(end 0.504 -0.248)
			(stroke
				(width 0.15)
				(type solid)
			)
			(layer "B.Fab")
		)
		(pad "1" smd roundrect
			(at -0.48 0)
			(size 0.59 0.64)
			(layers "B.Cu" "B.Mask" "B.Paste")
			(roundrect_rratio 0.25)
			(net 1 "GND")
			(pintype "passive")
		)
		(pad "2" smd roundrect
			(at 0.48 0)
			(size 0.59 0.64)
			(layers "B.Cu" "B.Mask" "B.Paste")
			(roundrect_rratio 0.25)
			(net 2 "VCC3V3")
			(pintype "passive")
		)
	)
	(footprint "antmicro-footprints:C_0402_1005Metric"
		(layer "B.Cu")
		(at 96.7 96.955)
		(descr "Capacitor SMD 0402")
		(tags "capacitor SMD 0402")
		(property "Reference" "C219"
			(at -9.2 0.2 0)
			(layer "B.SilkS")
			(effects
				(font
					(size 0.7 0.7)
					(thickness 0.15)
				)
				(justify right bottom mirror)
			)
		)
		(property "Value" "C_10n_0402"
			(at 0 -1.4 0)
			(layer "B.Fab")
			(effects
				(font
					(size 0.7 0.7)
					(thickness 0.15)
				)
				(justify right bottom mirror)
			)
		)
		(property "Datasheet" "https://www.murata.com/products/productdetail?partno=GRM155R71H103KA88%23"
			(at 0 0 0)
			(layer "F.Fab")
			(hide yes)
			(effects
				(font
					(size 1.27 1.27)
					(thickness 0.15)
				)
			)
		)
		(property "Description" "SMD Multilayer Ceramic Capacitor, 10000 pF, 50 V, 0402 [1005 Metric], ± 10%, X7R, GRM Series"
			(at 0 0 0)
			(layer "F.Fab")
			(hide yes)
			(effects
				(font
					(size 1.27 1.27)
					(thickness 0.15)
				)
			)
		)
		(property "Author" "Antmicro"
			(at 0 0 0)
			(layer "B.Fab")
			(hide yes)
			(effects
				(font
					(size 1 1)
					(thickness 0.15)
				)
				(justify mirror)
			)
		)
		(property "Dielectric" "X7R"
			(at 0 0 0)
			(layer "B.Fab")
			(hide yes)
			(effects
				(font
					(size 1 1)
					(thickness 0.15)
				)
				(justify mirror)
			)
		)
		(property "License" "Apache-2.0"
			(at 0 0 0)
			(layer "B.Fab")
			(hide yes)
			(effects
				(font
					(size 1 1)
					(thickness 0.15)
				)
				(justify mirror)
			)
		)
		(property "MPN" "GRM155R71H103KA88D"
			(at 0 0 0)
			(layer "B.Fab")
			(hide yes)
			(effects
				(font
					(size 1 1)
					(thickness 0.15)
				)
				(justify mirror)
			)
		)
		(property "Manufacturer" "Murata"
			(at 0 0 0)
			(layer "B.Fab")
			(hide yes)
			(effects
				(font
					(size 1 1)
					(thickness 0.15)
				)
				(justify mirror)
			)
		)
		(property "Val" "10n"
			(at 0 0 0)
			(layer "B.Fab")
			(hide yes)
			(effects
				(font
					(size 1 1)
					(thickness 0.15)
				)
				(justify mirror)
			)
		)
		(property "Voltage" "50V"
			(at 0 0 0)
			(layer "B.Fab")
			(hide yes)
			(effects
				(font
					(size 1 1)
					(thickness 0.15)
				)
				(justify mirror)
			)
		)
		(sheetname "/Ethernet/")
		(sheetfile "ethernet.kicad_sch")
		(attr smd)
		(fp_rect
			(start -0.925 0.47)
			(end 0.925 -0.47)
			(stroke
				(width 0.05)
				(type default)
			)
			(fill no)
			(layer "B.CrtYd")
		)
		(fp_line
			(start -0.494 -0.248)
			(end -0.494 0.25)
			(stroke
				(width 0.15)
				(type solid)
			)
			(layer "B.Fab")
		)
		(fp_line
			(start -0.494 0.25)
			(end 0.504 0.25)
			(stroke
				(width 0.15)
				(type solid)
			)
			(layer "B.Fab")
		)
		(fp_line
			(start 0.504 -0.248)
			(end -0.494 -0.248)
			(stroke
				(width 0.15)
				(type solid)
			)
			(layer "B.Fab")
		)
		(fp_line
			(start 0.504 0.25)
			(end 0.504 -0.248)
			(stroke
				(width 0.15)
				(type solid)
			)
			(layer "B.Fab")
		)
		(pad "1" smd roundrect
			(at -0.48 0)
			(size 0.59 0.64)
			(layers "B.Cu" "B.Mask" "B.Paste")
			(roundrect_rratio 0.25)
			(net 1 "GND")
			(pintype "passive")
		)
		(pad "2" smd roundrect
			(at 0.48 0)
			(size 0.59 0.64)
			(layers "B.Cu" "B.Mask" "B.Paste")
			(roundrect_rratio 0.25)
			(net 339 "VCC1V2")
			(pintype "passive")
		)
	)
)
